(kicad_pcb
	(version 20260206)
	(generator "pcbnew")
	(generator_version "10.0")
	(general
		(thickness 1.6)
		(legacy_teardrops no)
	)
	(paper "A4")
	(title_block
		(title "v2-tray-backplane — ms_tbp_v2.brd")
		(comment 1 "Open CloudServer (Microsoft) / footprints 113-115 of 164")
	)
	(layers
		(0 "F.Cu" signal "TOP")
		(4 "In1.Cu" signal "LYR2")
		(6 "In2.Cu" signal "LYR3")
		(8 "In3.Cu" signal "LYR4")
		(10 "In4.Cu" signal "LYR5")
		(12 "In5.Cu" signal "LYR6")
		(14 "In6.Cu" signal "LYR7")
		(2 "B.Cu" signal "BOTTOM")
		(9 "F.Adhes" user "F.Adhesive")
		(11 "B.Adhes" user "B.Adhesive")
		(13 "F.Paste" user "Package Geometry/Pastemask Top")
		(15 "B.Paste" user "Package Geometry/Pastemask Bottom")
		(5 "F.SilkS" user "Ref Des/Silkscreen Top")
		(7 "B.SilkS" user "Ref Des/Silkscreen Bottom")
		(1 "F.Mask" user "Board Geometry/Soldermask Top")
		(3 "B.Mask" user "Board Geometry/Soldermask Bottom")
		(17 "Dwgs.User" user "User.Drawings")
		(19 "Cmts.User" user "User.Comments")
		(21 "Eco1.User" user "User.Eco1")
		(23 "Eco2.User" user "User.Eco2")
		(25 "Edge.Cuts" user "Board Geometry/Outline")
		(27 "Margin" user)
		(31 "F.CrtYd" user "Package Geometry/Place Bound Top")
		(29 "B.CrtYd" user "Package Geometry/Place Bound Bottom")
		(35 "F.Fab" user "Ref Des/Assembly Top")
		(33 "B.Fab" user "Ref Des/Assembly Bottom")
	)
	(footprint ""
		(layer "F.Cu")
		(at -75.3618 8.255 180)
		(property "Reference" "R51"
			(at -3.2131 0.0127 0)
			(unlocked yes)
			(layer "F.SilkS")
			(effects
				(font
					(size 0.762 0.5334)
					(thickness 0.1016)
				)
			)
		)
		(property "Value" ""
			(at 0 0 180)
			(layer "F.Fab")
			(effects
				(font
					(size 1.27 1.27)
				)
			)
		)
		(duplicate_pad_numbers_are_jumpers no)
		(fp_line
			(start 0 -0.381)
			(end 0 0.381)
			(stroke
				(width 0.127)
				(type default)
			)
			(layer "F.SilkS")
		)
		(fp_poly
			(pts
				(xy 1.255601 0.656399) (xy -1.255601 0.656399) (xy -1.255601 -0.6564) (xy 1.255601 -0.6564)
			)
			(stroke
				(width 0)
				(type default)
			)
			(fill no)
			(layer "F.CrtYd")
		)
		(fp_line
			(start 0.800001 0.399999)
			(end 0.800001 -0.399999)
			(stroke
				(width 0.1)
				(type default)
			)
			(layer "F.Fab")
		)
		(fp_line
			(start 0.800001 -0.399999)
			(end -0.800001 -0.399999)
			(stroke
				(width 0.1)
				(type default)
			)
			(layer "F.Fab")
		)
		(fp_line
			(start -0.800001 0.399999)
			(end 0.800001 0.399999)
			(stroke
				(width 0.1)
				(type default)
			)
			(layer "F.Fab")
		)
		(fp_line
			(start -0.800001 -0.399999)
			(end -0.800001 0.399999)
			(stroke
				(width 0.1)
				(type default)
			)
			(layer "F.Fab")
		)
		(pad "1" smd rect
			(at -0.650001 0 180)
			(size 0.7112 0.8128)
			(layers "F.Cu" "F.Mask" "F.Paste")
			(net "ETH10G_B2_RS0")
		)
		(pad "2" smd rect
			(at 0.650001 0)
			(size 0.7112 0.8128)
			(layers "F.Cu" "F.Mask" "F.Paste")
			(net "GND")
		)
	)
	(footprint ""
		(layer "F.Cu")
		(at -296.164 8.382 180)
		(property "Reference" "R2"
			(at -2.667 0.0889 0)
			(unlocked yes)
			(layer "F.SilkS")
			(effects
				(font
					(size 0.762 0.5334)
					(thickness 0.1016)
				)
			)
		)
		(property "Value" ""
			(at 0 0 180)
			(layer "F.Fab")
			(effects
				(font
					(size 1.27 1.27)
				)
			)
		)
		(duplicate_pad_numbers_are_jumpers no)
		(fp_line
			(start 0 -0.381)
			(end 0 0.381)
			(stroke
				(width 0.127)
				(type default)
			)
			(layer "F.SilkS")
		)
		(fp_poly
			(pts
				(xy 1.255601 0.656399) (xy -1.255601 0.656399) (xy -1.255601 -0.6564) (xy 1.255601 -0.6564)
			)
			(stroke
				(width 0)
				(type default)
			)
			(fill no)
			(layer "F.CrtYd")
		)
		(fp_line
			(start 0.800001 0.399999)
			(end 0.800001 -0.399999)
			(stroke
				(width 0.1)
				(type default)
			)
			(layer "F.Fab")
		)
		(fp_line
			(start 0.800001 -0.399999)
			(end -0.800001 -0.399999)
			(stroke
				(width 0.1)
				(type default)
			)
			(layer "F.Fab")
		)
		(fp_line
			(start -0.800001 0.399999)
			(end 0.800001 0.399999)
			(stroke
				(width 0.1)
				(type default)
			)
			(layer "F.Fab")
		)
		(fp_line
			(start -0.800001 -0.399999)
			(end -0.800001 0.399999)
			(stroke
				(width 0.1)
				(type default)
			)
			(layer "F.Fab")
		)
		(pad "1" smd rect
			(at -0.650001 0 180)
			(size 0.7112 0.8128)
			(layers "F.Cu" "F.Mask" "F.Paste")
			(net "P3V3_B1_QSFP")
		)
		(pad "2" smd rect
			(at 0.650001 0)
			(size 0.7112 0.8128)
			(layers "F.Cu" "F.Mask" "F.Paste")
			(net "SKU_B1_ID0")
		)
	)
	(footprint ""
		(layer "F.Cu")
		(at -73.040001 45.360001 180)
		(property "Reference" "J19"
			(at 4.175999 18.143901 0)
			(unlocked yes)
			(layer "F.SilkS")
			(effects
				(font
					(size 0.762 0.5334)
					(thickness 0.1016)
				)
			)
		)
		(property "Value" ""
			(at 0 0 180)
			(layer "F.Fab")
			(effects
				(font
					(size 1.27 1.27)
				)
			)
		)
		(duplicate_pad_numbers_are_jumpers no)
		(fp_line
			(start 10.950001 15.3)
			(end -0.95 15.3)
			(stroke
				(width 0.127)
				(type default)
			)
			(layer "F.SilkS")
		)
		(fp_line
			(start 10.950001 5.609001)
			(end 10.950001 15.3)
			(stroke
				(width 0.127)
				(type default)
			)
			(layer "F.SilkS")
		)
		(fp_line
			(start 10.950001 -11.999999)
			(end 10.950001 4.212001)
			(stroke
				(width 0.127)
				(type default)
			)
			(layer "F.SilkS")
		)
		(fp_line
			(start -0.95 15.3)
			(end -0.95 13.356001)
			(stroke
				(width 0.127)
				(type default)
			)
			(layer "F.SilkS")
		)
		(fp_line
			(start -0.95 11.451001)
			(end -0.95 2.561001)
			(stroke
				(width 0.127)
				(type default)
			)
			(layer "F.SilkS")
		)
		(fp_line
			(start -0.95 0.656001)
			(end -0.95 -11.999999)
			(stroke
				(width 0.127)
				(type default)
			)
			(layer "F.SilkS")
		)
		(fp_line
			(start -0.95 -11.999999)
			(end 10.950001 -11.999999)
			(stroke
				(width 0.127)
				(type default)
			)
			(layer "F.SilkS")
		)
		(fp_poly
			(pts
				(arc
					(start -4.93 12.500001)
					(mid -3.486036 15.986037)
					(end 0 17.430001)
				)
				(arc
					(start 10.000001 17.430001)
					(mid 13.486037 15.986037)
					(end 14.930001 12.500001)
				)
				(arc
					(start 14.930001 -0.1)
					(mid 13.486037 -3.586036)
					(end 10.000001 -5.03)
				)
				(arc
					(start 0 -5.03)
					(mid -3.486036 -3.586036)
					(end -4.93 -0.1)
				)
			)
			(stroke
				(width 0)
				(type default)
			)
			(fill no)
			(layer "B.CrtYd")
		)
		(fp_poly
			(pts
				(xy 11.949999 16.300001) (xy -1.950001 16.300001) (xy -1.950001 -12.999999) (xy 11.949999 -12.999999)
			)
			(stroke
				(width 0)
				(type default)
			)
			(fill no)
			(layer "F.CrtYd")
		)
		(fp_line
			(start 10.950001 15.3)
			(end -0.95 15.3)
			(stroke
				(width 0.1)
				(type default)
			)
			(layer "F.Fab")
		)
		(fp_line
			(start 10.950001 -11.999999)
			(end 10.950001 15.3)
			(stroke
				(width 0.1)
				(type default)
			)
			(layer "F.Fab")
		)
		(fp_line
			(start -0.95 15.3)
			(end -0.95 -11.999999)
			(stroke
				(width 0.1)
				(type default)
			)
			(layer "F.Fab")
		)
		(fp_line
			(start -0.95 -11.999999)
			(end 10.950001 -11.999999)
			(stroke
				(width 0.1)
				(type default)
			)
			(layer "F.Fab")
		)
		(fp_text user "I6"
			(at 11.668999 11.285901 0)
			(unlocked yes)
			(layer "F.SilkS")
			(effects
				(font
					(size 0.762 0.5334)
					(thickness 0.1016)
				)
			)
		)
		(fp_text user "E6"
			(at 11.668999 4.808901 0)
			(unlocked yes)
			(layer "F.SilkS")
			(effects
				(font
					(size 0.762 0.5334)
					(thickness 0.1016)
				)
			)
		)
		(fp_text user "A6"
			(at 11.668999 -0.017099 0)
			(unlocked yes)
			(layer "F.SilkS")
			(effects
				(font
					(size 0.762 0.5334)
					(thickness 0.1016)
				)
			)
		)
		(fp_text user "A1"
			(at 0.746999 -1.160099 0)
			(unlocked yes)
			(layer "F.SilkS")
			(effects
				(font
					(size 0.762 0.5334)
					(thickness 0.1016)
				)
			)
		)
		(fp_text user "*"
			(at -0.396001 -1.077549 0)
			(unlocked yes)
			(layer "F.SilkS")
			(effects
				(font
					(size 0.381 0.381)
					(thickness 0.381)
				)
			)
		)
		(fp_text user "I6"
			(at 11.55 11.0809 0)
			(unlocked yes)
			(layer "B.SilkS")
			(effects
				(font
					(size 0.762 0.5334)
					(thickness 0.1016)
				)
				(justify mirror)
			)
		)
		(fp_text user "A6"
			(at 11.55 -0.1191 0)
			(unlocked yes)
			(layer "B.SilkS")
			(effects
				(font
					(size 0.762 0.5334)
					(thickness 0.1016)
				)
				(justify mirror)
			)
		)
		(fp_text user "E6"
			(at 11.323559 5.268641 0)
			(unlocked yes)
			(layer "B.SilkS")
			(effects
				(font
					(size 0.762 0.5334)
					(thickness 0.1016)
				)
				(justify mirror)
			)
		)
		(fp_text user "E1"
			(at -1.241821 5.906181 0)
			(unlocked yes)
			(layer "B.SilkS")
			(effects
				(font
					(size 0.762 0.5334)
					(thickness 0.1016)
				)
				(justify mirror)
			)
		)
		(fp_text user "I1"
			(at -1.285001 10.777901 0)
			(unlocked yes)
			(layer "B.SilkS")
			(effects
				(font
					(size 0.762 0.5334)
					(thickness 0.1016)
				)
				(justify mirror)
			)
		)
		(fp_text user "A1"
			(at -1.549999 -0.1191 0)
			(unlocked yes)
			(layer "B.SilkS")
			(effects
				(font
					(size 0.762 0.5334)
					(thickness 0.1016)
				)
				(justify mirror)
			)
		)
		(pad "A1" thru_hole circle
			(at 0 0 180)
			(size 0.8128 0.8128)
			(drill 0.508)
			(layers "*.Cu" "*.Mask")
			(remove_unused_layers no)
			(net "ETH40G_B2_TX3P")
		)
		(pad "A2" thru_hole circle
			(at 2.000001 -0.1 180)
			(size 0.8128 0.8128)
			(drill 0.508)
			(layers "*.Cu" "*.Mask")
			(remove_unused_layers no)
			(net "GND")
		)
		(pad "A3" thru_hole circle
			(at 4 0 180)
			(size 0.8128 0.8128)
			(drill 0.508)
			(layers "*.Cu" "*.Mask")
			(remove_unused_layers no)
			(net "ETH40G_B2_RX2P")
		)
		(pad "A4" thru_hole circle
			(at 6.000001 -0.1 180)
			(size 0.8128 0.8128)
			(drill 0.508)
			(layers "*.Cu" "*.Mask")
			(remove_unused_layers no)
			(net "GND")
		)
		(pad "A5" thru_hole circle
			(at 7.999999 0 180)
			(size 0.8128 0.8128)
			(drill 0.508)
			(layers "*.Cu" "*.Mask")
			(remove_unused_layers no)
			(net "ETH40G_B2_RX1P")
		)
		(pad "A6" thru_hole circle
			(at 10 -0.1 180)
			(size 0.8128 0.8128)
			(drill 0.508)
			(layers "*.Cu" "*.Mask")
			(remove_unused_layers no)
			(net "GND")
		)
		(pad "B1" thru_hole circle
			(at 0 1.4 180)
			(size 0.8128 0.8128)
			(drill 0.508)
			(layers "*.Cu" "*.Mask")
			(remove_unused_layers no)
			(net "ETH40G_B2_TX3N")
		)
		(pad "B2" thru_hole circle
			(at 2.000001 1.3 180)
			(size 0.8128 0.8128)
			(drill 0.508)
			(layers "*.Cu" "*.Mask")
			(remove_unused_layers no)
			(net "ETH40G_B2_RX3P")
		)
		(pad "B3" thru_hole circle
			(at 4 1.4 180)
			(size 0.8128 0.8128)
			(drill 0.508)
			(layers "*.Cu" "*.Mask")
			(remove_unused_layers no)
			(net "ETH40G_B2_RX2N")
		)
		(pad "B4" thru_hole circle
			(at 6.000001 1.3 180)
			(size 0.8128 0.8128)
			(drill 0.508)
			(layers "*.Cu" "*.Mask")
			(remove_unused_layers no)
			(net "ETH40G_B2_TX2P")
		)
		(pad "B5" thru_hole circle
			(at 7.999999 1.4 180)
			(size 0.8128 0.8128)
			(drill 0.508)
			(layers "*.Cu" "*.Mask")
			(remove_unused_layers no)
			(net "ETH40G_B2_RX1N")
		)
		(pad "B6" thru_hole circle
			(at 10 1.3 180)
			(size 0.8128 0.8128)
			(drill 0.508)
			(layers "*.Cu" "*.Mask")
			(remove_unused_layers no)
			(net "ETH40G_B2_TX1P")
		)
		(pad "C1" thru_hole circle
			(at 0 2.799999 180)
			(size 0.8128 0.8128)
			(drill 0.508)
			(layers "*.Cu" "*.Mask")
			(remove_unused_layers no)
			(net "GND")
		)
		(pad "C2" thru_hole circle
			(at 2.000001 2.7 180)
			(size 0.8128 0.8128)
			(drill 0.508)
			(layers "*.Cu" "*.Mask")
			(remove_unused_layers no)
			(net "ETH40G_B2_RX3N")
		)
		(pad "C3" thru_hole circle
			(at 4 2.799999 180)
			(size 0.8128 0.8128)
			(drill 0.508)
			(layers "*.Cu" "*.Mask")
			(remove_unused_layers no)
			(net "GND")
		)
		(pad "C4" thru_hole circle
			(at 6.000001 2.7 180)
			(size 0.8128 0.8128)
			(drill 0.508)
			(layers "*.Cu" "*.Mask")
			(remove_unused_layers no)
			(net "ETH40G_B2_TX2N")
		)
		(pad "C5" thru_hole circle
			(at 7.999999 2.799999 180)
			(size 0.8128 0.8128)
			(drill 0.508)
			(layers "*.Cu" "*.Mask")
			(remove_unused_layers no)
			(net "GND")
		)
		(pad "C6" thru_hole circle
			(at 10 2.7 180)
			(size 0.8128 0.8128)
			(drill 0.508)
			(layers "*.Cu" "*.Mask")
			(remove_unused_layers no)
			(net "ETH40G_B2_TX1N")
		)
		(pad "D1" thru_hole circle
			(at 0 4.199999 180)
			(size 0.8128 0.8128)
			(drill 0.508)
			(layers "*.Cu" "*.Mask")
			(remove_unused_layers no)
			(net "ETH10G_B2_RXP")
		)
		(pad "D2" thru_hole circle
			(at 2.000001 4.099999 180)
			(size 0.8128 0.8128)
			(drill 0.508)
			(layers "*.Cu" "*.Mask")
			(remove_unused_layers no)
			(net "GND")
		)
		(pad "D3" thru_hole circle
			(at 4 4.199999 180)
			(size 0.8128 0.8128)
			(drill 0.508)
			(layers "*.Cu" "*.Mask")
			(remove_unused_layers no)
			(net "ETH10G_B2_SDA")
		)
		(pad "D4" thru_hole circle
			(at 6.000001 4.099999 180)
			(size 0.8128 0.8128)
			(drill 0.508)
			(layers "*.Cu" "*.Mask")
			(remove_unused_layers no)
			(net "GND")
		)
		(pad "D5" thru_hole circle
			(at 7.999999 4.199999 180)
			(size 0.8128 0.8128)
			(drill 0.508)
			(layers "*.Cu" "*.Mask")
			(remove_unused_layers no)
			(net "P3V3_B2_QSFP")
		)
		(pad "D6" thru_hole circle
			(at 10 4.099999 180)
			(size 0.8128 0.8128)
			(drill 0.508)
			(layers "*.Cu" "*.Mask")
			(remove_unused_layers no)
			(net "GND")
		)
		(pad "E1" thru_hole circle
			(at 0 5.599999 180)
			(size 0.8128 0.8128)
			(drill 0.508)
			(layers "*.Cu" "*.Mask")
			(remove_unused_layers no)
			(net "ETH10G_B2_RXN")
		)
		(pad "E2" thru_hole circle
			(at 2.000001 5.499999 180)
			(size 0.8128 0.8128)
			(drill 0.508)
			(layers "*.Cu" "*.Mask")
			(remove_unused_layers no)
			(net "Net_14")
		)
		(pad "E3" thru_hole circle
			(at 4 5.599999 180)
			(size 0.8128 0.8128)
			(drill 0.508)
			(layers "*.Cu" "*.Mask")
			(remove_unused_layers no)
			(net "ETH10G_B2_SCL")
		)
		(pad "E4" thru_hole circle
			(at 6.000001 5.499999 180)
			(size 0.8128 0.8128)
			(drill 0.508)
			(layers "*.Cu" "*.Mask")
			(remove_unused_layers no)
			(net "ETH40G_B2_SDA")
		)
		(pad "E5" thru_hole circle
			(at 7.999999 5.599999 180)
			(size 0.8128 0.8128)
			(drill 0.508)
			(layers "*.Cu" "*.Mask")
			(remove_unused_layers no)
			(net "P3V3_B2_QSFP")
		)
		(pad "E6" thru_hole circle
			(at 10 5.499999 180)
			(size 0.8128 0.8128)
			(drill 0.508)
			(layers "*.Cu" "*.Mask")
			(remove_unused_layers no)
			(net "ETH40G_B2_RX0P")
		)
		(pad "F1" thru_hole circle
			(at 0 7.000001 180)
			(size 0.8128 0.8128)
			(drill 0.508)
			(layers "*.Cu" "*.Mask")
			(remove_unused_layers no)
			(net "GND")
		)
		(pad "F2" thru_hole circle
			(at 2.000001 6.899999 180)
			(size 0.8128 0.8128)
			(drill 0.508)
			(layers "*.Cu" "*.Mask")
			(remove_unused_layers no)
			(net "SKU_B2_ID2")
		)
		(pad "F3" thru_hole circle
			(at 4 7.000001 180)
			(size 0.8128 0.8128)
			(drill 0.508)
			(layers "*.Cu" "*.Mask")
			(remove_unused_layers no)
			(net "SKU_B2_ID0")
		)
		(pad "F4" thru_hole circle
			(at 6.000001 6.899999 180)
			(size 0.8128 0.8128)
			(drill 0.508)
			(layers "*.Cu" "*.Mask")
			(remove_unused_layers no)
			(net "ETH40G_B2_SCL")
		)
		(pad "F5" thru_hole circle
			(at 7.999999 7.000001 180)
			(size 0.8128 0.8128)
			(drill 0.508)
			(layers "*.Cu" "*.Mask")
			(remove_unused_layers no)
			(net "GND")
		)
		(pad "F6" thru_hole circle
			(at 10 6.899999 180)
			(size 0.8128 0.8128)
			(drill 0.508)
			(layers "*.Cu" "*.Mask")
			(remove_unused_layers no)
			(net "ETH40G_B2_RX0N")
		)
		(pad "G1" thru_hole circle
			(at 0 8.400001 180)
			(size 0.8128 0.8128)
			(drill 0.508)
			(layers "*.Cu" "*.Mask")
			(remove_unused_layers no)
			(net "ETH10G_B2_TXP")
		)
		(pad "G2" thru_hole circle
			(at 2.000001 8.300001 180)
			(size 0.8128 0.8128)
			(drill 0.508)
			(layers "*.Cu" "*.Mask")
			(remove_unused_layers no)
			(net "GND")
		)
		(pad "G3" thru_hole circle
			(at 4 8.400001 180)
			(size 0.8128 0.8128)
			(drill 0.508)
			(layers "*.Cu" "*.Mask")
			(remove_unused_layers no)
			(net "SERIAL_B2_RX1")
		)
		(pad "G4" thru_hole circle
			(at 6.000001 8.300001 180)
			(size 0.8128 0.8128)
			(drill 0.508)
			(layers "*.Cu" "*.Mask")
			(remove_unused_layers no)
			(net "SERIAL_B2_RX2")
		)
		(pad "G5" thru_hole circle
			(at 7.999999 8.400001 180)
			(size 0.8128 0.8128)
			(drill 0.508)
			(layers "*.Cu" "*.Mask")
			(remove_unused_layers no)
			(net "PSU_B2_ALERT_N")
		)
		(pad "G6" thru_hole circle
			(at 10 8.300001 180)
			(size 0.8128 0.8128)
			(drill 0.508)
			(layers "*.Cu" "*.Mask")
			(remove_unused_layers no)
			(net "GND")
		)
		(pad "H1" thru_hole circle
			(at 0 9.800001 180)
			(size 0.8128 0.8128)
			(drill 0.508)
			(layers "*.Cu" "*.Mask")
			(remove_unused_layers no)
			(net "ETH10G_B2_TXN")
		)
		(pad "H2" thru_hole circle
			(at 2.000001 9.700001 180)
			(size 0.8128 0.8128)
			(drill 0.508)
			(layers "*.Cu" "*.Mask")
			(remove_unused_layers no)
			(net "BLADE_B2_EN1")
		)
		(pad "H3" thru_hole circle
			(at 4 9.800001 180)
			(size 0.8128 0.8128)
			(drill 0.508)
			(layers "*.Cu" "*.Mask")
			(remove_unused_layers no)
			(net "SERIAL_B2_TX1")
		)
		(pad "H4" thru_hole circle
			(at 6.000001 9.700001 180)
			(size 0.8128 0.8128)
			(drill 0.508)
			(layers "*.Cu" "*.Mask")
			(remove_unused_layers no)
			(net "SERIAL_B2_TX2")
		)
		(pad "H5" thru_hole circle
			(at 7.999999 9.800001 180)
			(size 0.8128 0.8128)
			(drill 0.508)
			(layers "*.Cu" "*.Mask")
			(remove_unused_layers no)
			(net "ETH40G_B2_PRES_N")
		)
		(pad "H6" thru_hole circle
			(at 10 9.700001 180)
			(size 0.8128 0.8128)
			(drill 0.508)
			(layers "*.Cu" "*.Mask")
			(remove_unused_layers no)
			(net "ETH40G_B2_TX0P")
		)
		(pad "I1" thru_hole circle
			(at 0 11.2 180)
			(size 0.8128 0.8128)
			(drill 0.508)
			(layers "*.Cu" "*.Mask")
			(remove_unused_layers no)
			(net "GND")
		)
		(pad "I2" thru_hole circle
			(at 2.000001 11.100001 180)
			(size 0.8128 0.8128)
			(drill 0.508)
			(layers "*.Cu" "*.Mask")
			(remove_unused_layers no)
			(net "ETH10G_B2_PRES_N")
		)
		(pad "I3" thru_hole circle
			(at 4 11.2 180)
			(size 0.8128 0.8128)
			(drill 0.508)
			(layers "*.Cu" "*.Mask")
			(remove_unused_layers no)
			(net "P3V3_B2_QSFP")
		)
		(pad "I4" thru_hole circle
			(at 6.000001 11.100001 180)
			(size 0.8128 0.8128)
			(drill 0.508)
			(layers "*.Cu" "*.Mask")
			(remove_unused_layers no)
			(net "SKU_B2_ID1")
		)
		(pad "I5" thru_hole circle
			(at 7.999999 11.2 180)
			(size 0.8128 0.8128)
			(drill 0.508)
			(layers "*.Cu" "*.Mask")
			(remove_unused_layers no)
			(net "BLADE_B2_MATED_N")
		)
		(pad "I6" thru_hole circle
			(at 10 11.100001 180)
			(size 0.8128 0.8128)
			(drill 0.508)
			(layers "*.Cu" "*.Mask")
			(remove_unused_layers no)
			(net "ETH40G_B2_TX0N")
		)
		(pad "J2" thru_hole circle
			(at 2.000001 12.5 180)
			(size 0.8128 0.8128)
			(drill 0.508)
			(layers "*.Cu" "*.Mask")
			(remove_unused_layers no)
			(net "GND")
		)
		(pad "J4" thru_hole circle
			(at 6.000001 12.5 180)
			(size 0.8128 0.8128)
			(drill 0.508)
			(layers "*.Cu" "*.Mask")
			(remove_unused_layers no)
			(net "GND")
		)
		(pad "J6" thru_hole circle
			(at 10 12.5 180)
			(size 0.8128 0.8128)
			(drill 0.508)
			(layers "*.Cu" "*.Mask")
			(remove_unused_layers no)
			(net "GND")
		)
	)
)
